(kicad_pcb
	(version 20260206)
	(generator "pcbnew")
	(generator_version "10.0")
	(general
		(thickness 1.6)
		(legacy_teardrops no)
	)
	(paper "A4")
	(title_block
		(title "Wiwynn_Tioga_Pass_MB.brd")
		(comment 1 "Tioga Pass / footprints 321-327 of 4770")
	)
	(layers
		(0 "F.Cu" signal "TOP")
		(4 "In1.Cu" signal "L2GND")
		(6 "In2.Cu" signal "L3")
		(8 "In3.Cu" signal "L4GND")
		(10 "In4.Cu" signal "L5")
		(12 "In5.Cu" signal "L6GND")
		(14 "In6.Cu" signal "L7VCC")
		(16 "In7.Cu" signal "L8VCC")
		(18 "In8.Cu" signal "L9GND")
		(20 "In9.Cu" signal "L10")
		(22 "In10.Cu" signal "L11GND")
		(24 "In11.Cu" signal "L12")
		(26 "In12.Cu" signal "L13GND")
		(2 "B.Cu" signal "BOTTOM")
		(9 "F.Adhes" user "F.Adhesive")
		(11 "B.Adhes" user "B.Adhesive")
		(13 "F.Paste" user "Package Geometry/Pastemask Top")
		(15 "B.Paste" user "Package Geometry/Pastemask Bottom")
		(5 "F.SilkS" user "Ref Des/Silkscreen Top")
		(7 "B.SilkS" user "Ref Des/Silkscreen Bottom")
		(1 "F.Mask" user "Board Geometry/Soldermask Top")
		(3 "B.Mask" user "Board Geometry/Soldermask Bottom")
		(17 "Dwgs.User" user "User.Drawings")
		(19 "Cmts.User" user "User.Comments")
		(21 "Eco1.User" user "User.Eco1")
		(23 "Eco2.User" user "User.Eco2")
		(25 "Edge.Cuts" user "Board Geometry/Outline")
		(27 "Margin" user)
		(31 "F.CrtYd" user "Package Geometry/Place Bound Top")
		(29 "B.CrtYd" user "Package Geometry/Place Bound Bottom")
		(35 "F.Fab" user "Ref Des/Assembly Top")
		(33 "B.Fab" user "Ref Des/Assembly Bottom")
	)
	(footprint ""
		(layer "F.Cu")
		(at 388.0104 -0.254)
		(property "Reference" "R8G8"
			(at 0 0 0)
			(layer "F.SilkS")
			(hide yes)
			(effects
				(font
					(size 1.27 1.27)
				)
			)
		)
		(property "Value" ""
			(at 0 0 0)
			(layer "F.Fab")
			(effects
				(font
					(size 1.27 1.27)
				)
			)
		)
		(duplicate_pad_numbers_are_jumpers no)
		(fp_poly
			(pts
				(xy -0.2794 -0.1016) (xy 0.2794 -0.1016) (xy 0.2794 0.9906) (xy -0.2794 0.9906)
			)
			(stroke
				(width 0)
				(type default)
			)
			(fill no)
			(layer "F.CrtYd")
		)
		(fp_line
			(start -0.2794 -0.1016)
			(end -0.2794 0.9906)
			(stroke
				(width 0.1)
				(type default)
			)
			(layer "F.Fab")
		)
		(fp_line
			(start -0.2794 0.9906)
			(end 0.2794 0.9906)
			(stroke
				(width 0.1)
				(type default)
			)
			(layer "F.Fab")
		)
		(fp_line
			(start 0.2794 -0.1016)
			(end -0.2794 -0.1016)
			(stroke
				(width 0.1)
				(type default)
			)
			(layer "F.Fab")
		)
		(fp_line
			(start 0.2794 0.9906)
			(end 0.2794 -0.1016)
			(stroke
				(width 0.1)
				(type default)
			)
			(layer "F.Fab")
		)
		(pad "1" smd rect
			(at 0 0)
			(size 0.508 0.508)
			(layers "F.Cu" "F.Mask" "F.Paste")
			(net "JTAG_BMC_TDI")
		)
		(pad "2" smd rect
			(at 0 0.889)
			(size 0.508 0.508)
			(layers "F.Cu" "F.Mask" "F.Paste")
			(net "JTAG_TDI")
		)
		(zone
			(layer "F.Cu")
			(hatch none 0.5)
			(connect_pads
				(clearance 0)
			)
			(min_thickness 0.25)
			(keepout
				(tracks allowed)
				(vias not_allowed)
				(pads allowed)
				(copperpour not_allowed)
				(footprints allowed)
			)
			(placement
				(enabled no)
				(sheetname "")
			)
			(fill
				(thermal_gap 0.5)
				(thermal_bridge_width 0.5)
				(island_removal_mode 0)
			)
			(polygon
				(pts
					(xy 387.7564 0) (xy 388.2644 0) (xy 388.2644 0.381) (xy 387.7564 0.381)
				)
			)
		)
		(zone
			(layer "F.Cu")
			(hatch none 0.5)
			(connect_pads
				(clearance 0)
			)
			(min_thickness 0.25)
			(keepout
				(tracks not_allowed)
				(vias allowed)
				(pads allowed)
				(copperpour not_allowed)
				(footprints allowed)
			)
			(placement
				(enabled no)
				(sheetname "")
			)
			(fill
				(thermal_gap 0.5)
				(thermal_bridge_width 0.5)
				(island_removal_mode 0)
			)
			(polygon
				(pts
					(xy 387.7564 0.381) (xy 388.2644 0.381) (xy 388.2644 0) (xy 387.7564 0)
				)
			)
		)
	)
	(footprint ""
		(layer "F.Cu")
		(at 441.404756 -147.621244 90)
		(property "Reference" "C25W101"
			(at -0.8382 -0.67818 90)
			(unlocked yes)
			(layer "F.SilkS")
			(effects
				(font
					(size 0.4064 0.254)
					(thickness 0.1524)
				)
				(justify left)
			)
		)
		(property "Value" ""
			(at 0 0 90)
			(layer "F.Fab")
			(effects
				(font
					(size 1.27 1.27)
				)
			)
		)
		(duplicate_pad_numbers_are_jumpers no)
		(fp_poly
			(pts
				(xy 0.3048 -0.1016) (xy 0.3048 0.9906) (xy -0.3048 0.9906) (xy -0.3048 -0.1016)
			)
			(stroke
				(width 0)
				(type default)
			)
			(fill no)
			(layer "F.CrtYd")
		)
		(fp_line
			(start 0.3048 -0.1016)
			(end -0.3048 -0.1016)
			(stroke
				(width 0.1)
				(type default)
			)
			(layer "F.Fab")
		)
		(fp_line
			(start -0.3048 -0.1016)
			(end -0.3048 0.9906)
			(stroke
				(width 0.1)
				(type default)
			)
			(layer "F.Fab")
		)
		(fp_line
			(start 0.3048 0.9906)
			(end 0.3048 -0.1016)
			(stroke
				(width 0.1)
				(type default)
			)
			(layer "F.Fab")
		)
		(fp_line
			(start -0.3048 0.9906)
			(end 0.3048 0.9906)
			(stroke
				(width 0.1)
				(type default)
			)
			(layer "F.Fab")
		)
		(pad "1" smd rect
			(at 0 0 90)
			(size 0.508 0.508)
			(layers "F.Cu" "F.Mask" "F.Paste")
			(net "P3V3_STBY")
		)
		(pad "2" smd rect
			(at 0 0.889 90)
			(size 0.508 0.508)
			(layers "F.Cu" "F.Mask" "F.Paste")
			(net "GND")
		)
		(zone
			(layer "F.Cu")
			(hatch none 0.5)
			(connect_pads
				(clearance 0)
			)
			(min_thickness 0.25)
			(keepout
				(tracks allowed)
				(vias not_allowed)
				(pads allowed)
				(copperpour not_allowed)
				(footprints allowed)
			)
			(placement
				(enabled no)
				(sheetname "")
			)
			(fill
				(thermal_gap 0.5)
				(thermal_bridge_width 0.5)
				(island_removal_mode 0)
			)
			(polygon
				(pts
					(xy 441.658756 -147.367244) (xy 441.658756 -147.875244) (xy 442.039756 -147.875244) (xy 442.039756 -147.367244)
				)
			)
		)
		(zone
			(layer "F.Cu")
			(hatch none 0.5)
			(connect_pads
				(clearance 0)
			)
			(min_thickness 0.25)
			(keepout
				(tracks not_allowed)
				(vias allowed)
				(pads allowed)
				(copperpour not_allowed)
				(footprints allowed)
			)
			(placement
				(enabled no)
				(sheetname "")
			)
			(fill
				(thermal_gap 0.5)
				(thermal_bridge_width 0.5)
				(island_removal_mode 0)
			)
			(polygon
				(pts
					(xy 442.039756 -147.367244) (xy 442.039756 -147.875244) (xy 441.658756 -147.875244) (xy 441.658756 -147.367244)
				)
			)
		)
	)
	(footprint ""
		(layer "F.Cu")
		(at 182.626 -84.1248)
		(property "Reference" ""
			(at 0 0 0)
			(layer "F.SilkS")
			(hide yes)
			(effects
				(font
					(size 1.27 1.27)
				)
			)
		)
		(property "Value" ""
			(at 0 0 0)
			(layer "F.Fab")
			(effects
				(font
					(size 1.27 1.27)
				)
			)
		)
		(duplicate_pad_numbers_are_jumpers no)
		(fp_poly
			(pts
				(arc
					(start 2.032 0)
					(mid -2.032 0)
					(end 2.032 0)
				)
			)
			(stroke
				(width 0)
				(type default)
			)
			(fill no)
			(layer "F.CrtYd")
		)
		(pad "1" smd circle
			(at 0 0)
			(size 1.016 1.016)
			(layers "F.Cu" "F.Mask" "F.Paste")
			(net "Net_393")
		)
		(zone
			(layer "F.Cu")
			(hatch none 0.5)
			(connect_pads
				(clearance 0)
			)
			(min_thickness 0.25)
			(keepout
				(tracks not_allowed)
				(vias allowed)
				(pads allowed)
				(copperpour not_allowed)
				(footprints allowed)
			)
			(placement
				(enabled no)
				(sheetname "")
			)
			(fill
				(thermal_gap 0.5)
				(thermal_bridge_width 0.5)
				(island_removal_mode 0)
			)
			(polygon
				(pts
					(arc
						(start 184.15 -84.1248)
						(mid 181.102 -84.1248)
						(end 184.15 -84.1248)
					)
				)
			)
		)
		(zone
			(layers "F.Cu" "B.Cu" "In1.Cu" "In2.Cu" "In3.Cu" "In4.Cu" "In5.Cu" "In6.Cu"
				"In7.Cu" "In8.Cu" "In9.Cu" "In10.Cu" "In11.Cu" "In12.Cu"
			)
			(hatch none 0.5)
			(connect_pads
				(clearance 0)
			)
			(min_thickness 0.25)
			(keepout
				(tracks allowed)
				(vias not_allowed)
				(pads allowed)
				(copperpour not_allowed)
				(footprints allowed)
			)
			(placement
				(enabled no)
				(sheetname "")
			)
			(fill
				(thermal_gap 0.5)
				(thermal_bridge_width 0.5)
				(island_removal_mode 0)
			)
			(polygon
				(pts
					(arc
						(start 184.15 -84.1248)
						(mid 181.102 -84.1248)
						(end 184.15 -84.1248)
					)
				)
			)
		)
	)
	(footprint ""
		(layer "F.Cu")
		(at 487.39679 -58.51144)
		(property "Reference" "F30W1"
			(at 0 0 0)
			(layer "F.SilkS")
			(hide yes)
			(effects
				(font
					(size 1.27 1.27)
				)
			)
		)
		(property "Value" "*"
			(at -2.3241 1.30175 0)
			(unlocked yes)
			(layer "F.Fab")
			(hide yes)
			(effects
				(font
					(size 0.889 0.889)
					(thickness 0.1524)
				)
			)
		)
		(property "Device Type" "POLYSW-1D1A6V-2-GP-U_DISCRET-GA"
			(at -2.3241 -0.22225 0)
			(unlocked yes)
			(layer "F.Fab")
			(hide yes)
			(effects
				(font
					(size 0.889 0.889)
					(thickness 0.1524)
				)
			)
		)
		(duplicate_pad_numbers_are_jumpers no)
		(fp_line
			(start -1.2065 -2.2479)
			(end -1.2065 2.2479)
			(stroke
				(width 0.1524)
				(type default)
			)
			(layer "F.SilkS")
		)
		(fp_line
			(start -1.2065 2.2479)
			(end 1.2065 2.2479)
			(stroke
				(width 0.1524)
				(type default)
			)
			(layer "F.SilkS")
		)
		(fp_line
			(start 1.2065 -2.2479)
			(end -1.2065 -2.2479)
			(stroke
				(width 0.1524)
				(type default)
			)
			(layer "F.SilkS")
		)
		(fp_line
			(start 1.2065 2.2479)
			(end 1.2065 -2.2479)
			(stroke
				(width 0.1524)
				(type default)
			)
			(layer "F.SilkS")
		)
		(fp_rect
			(start -0.8255 1.6002)
			(end 0.8255 -1.6002)
			(stroke
				(width 0)
				(type default)
			)
			(fill no)
			(layer "F.CrtYd")
		)
		(fp_poly
			(pts
				(xy -1.4605 2.3241) (xy -1.4605 -2.3241) (xy 1.4605 -2.3241) (xy 1.4605 1.59512) (xy 0.8255 1.59512)
				(xy 0.8255 -1.6002) (xy -0.8255 -1.6002) (xy -0.8255 1.6002) (xy 1.4605 1.6002) (xy 1.4605 2.3241)
			)
			(stroke
				(width 0)
				(type default)
			)
			(fill no)
			(layer "F.CrtYd")
		)
		(fp_rect
			(start -1.4605 2.3241)
			(end 1.4605 -2.3241)
			(stroke
				(width 0)
				(type default)
			)
			(fill no)
			(layer "F.Fab")
		)
		(pad "1" smd rect
			(at 0 -1.417574)
			(size 1.905 1.143)
			(layers "F.Cu" "F.Mask" "F.Paste")
			(net "P5V_STBY")
		)
		(pad "2" smd rect
			(at 0 1.417574)
			(size 1.905 1.143)
			(layers "F.Cu" "F.Mask" "F.Paste")
			(net "P5V_STBY_USBC")
		)
	)
	(footprint ""
		(layer "F.Cu")
		(at 339.222588 -119.211598 -90)
		(property "Reference" "C844"
			(at -0.8382 -0.67818 270)
			(unlocked yes)
			(layer "F.SilkS")
			(effects
				(font
					(size 0.4064 0.254)
					(thickness 0.1524)
				)
				(justify left)
			)
		)
		(property "Value" ""
			(at 0 0 270)
			(layer "F.Fab")
			(effects
				(font
					(size 1.27 1.27)
				)
			)
		)
		(duplicate_pad_numbers_are_jumpers no)
		(fp_poly
			(pts
				(xy 0.3048 -0.1016) (xy 0.3048 0.9906) (xy -0.3048 0.9906) (xy -0.3048 -0.1016)
			)
			(stroke
				(width 0)
				(type default)
			)
			(fill no)
			(layer "F.CrtYd")
		)
		(fp_line
			(start -0.3048 0.9906)
			(end 0.3048 0.9906)
			(stroke
				(width 0.1)
				(type default)
			)
			(layer "F.Fab")
		)
		(fp_line
			(start 0.3048 0.9906)
			(end 0.3048 -0.1016)
			(stroke
				(width 0.1)
				(type default)
			)
			(layer "F.Fab")
		)
		(fp_line
			(start -0.3048 -0.1016)
			(end -0.3048 0.9906)
			(stroke
				(width 0.1)
				(type default)
			)
			(layer "F.Fab")
		)
		(fp_line
			(start 0.3048 -0.1016)
			(end -0.3048 -0.1016)
			(stroke
				(width 0.1)
				(type default)
			)
			(layer "F.Fab")
		)
		(pad "1" smd rect
			(at 0 0 270)
			(size 0.508 0.508)
			(layers "F.Cu" "F.Mask" "F.Paste")
			(net "P3E_CPU0_PE1_PCH_TXN<9>")
		)
		(pad "2" smd rect
			(at 0 0.889 270)
			(size 0.508 0.508)
			(layers "F.Cu" "F.Mask" "F.Paste")
			(net "P3E_CPU0_PE1_PCH_CON_TXN<9>")
		)
		(zone
			(layer "F.Cu")
			(hatch none 0.5)
			(connect_pads
				(clearance 0)
			)
			(min_thickness 0.25)
			(keepout
				(tracks not_allowed)
				(vias allowed)
				(pads allowed)
				(copperpour not_allowed)
				(footprints allowed)
			)
			(placement
				(enabled no)
				(sheetname "")
			)
			(fill
				(thermal_gap 0.5)
				(thermal_bridge_width 0.5)
				(island_removal_mode 0)
			)
			(polygon
				(pts
					(xy 338.587588 -119.465598) (xy 338.587588 -118.957598) (xy 338.968588 -118.957598) (xy 338.968588 -119.465598)
				)
			)
		)
		(zone
			(layer "F.Cu")
			(hatch none 0.5)
			(connect_pads
				(clearance 0)
			)
			(min_thickness 0.25)
			(keepout
				(tracks allowed)
				(vias not_allowed)
				(pads allowed)
				(copperpour not_allowed)
				(footprints allowed)
			)
			(placement
				(enabled no)
				(sheetname "")
			)
			(fill
				(thermal_gap 0.5)
				(thermal_bridge_width 0.5)
				(island_removal_mode 0)
			)
			(polygon
				(pts
					(xy 338.968588 -119.465598) (xy 338.968588 -118.957598) (xy 338.587588 -118.957598) (xy 338.587588 -119.465598)
				)
			)
		)
	)
	(footprint ""
		(layer "F.Cu")
		(at 185.886598 -126.97333 90)
		(property "Reference" "Q12W2"
			(at 0 0 90)
			(layer "F.SilkS")
			(hide yes)
			(effects
				(font
					(size 1.27 1.27)
				)
			)
		)
		(property "Value" "*"
			(at -4.572 -7.6835 90)
			(unlocked yes)
			(layer "F.Fab")
			(hide yes)
			(effects
				(font
					(size 1.27 1.016)
					(thickness 0.1524)
				)
			)
		)
		(property "Device Type" "BSL308C-H6327-GP_DISCRET-GB1-BA"
			(at -4.572 -9.2075 90)
			(unlocked yes)
			(layer "F.Fab")
			(hide yes)
			(effects
				(font
					(size 1.27 1.016)
					(thickness 0.1524)
				)
			)
		)
		(duplicate_pad_numbers_are_jumpers no)
		(fp_line
			(start 1.102868 -0.081534)
			(end 1.102868 0.081534)
			(stroke
				(width 0.1524)
				(type default)
			)
			(layer "F.SilkS")
		)
		(fp_line
			(start -1.8796 -0.081534)
			(end 1.102868 -0.081534)
			(stroke
				(width 0.1524)
				(type default)
			)
			(layer "F.SilkS")
		)
		(fp_line
			(start -1.8796 -0.081534)
			(end -1.524 0)
			(stroke
				(width 0.1524)
				(type default)
			)
			(layer "F.SilkS")
		)
		(fp_line
			(start -1.524 0)
			(end -1.8796 0.081534)
			(stroke
				(width 0.1524)
				(type default)
			)
			(layer "F.SilkS")
		)
		(fp_line
			(start 1.102868 0.081534)
			(end -1.8796 0.081534)
			(stroke
				(width 0.1524)
				(type default)
			)
			(layer "F.SilkS")
		)
		(fp_line
			(start -1.8796 0.081534)
			(end -1.8796 -0.081534)
			(stroke
				(width 0.1524)
				(type default)
			)
			(layer "F.SilkS")
		)
		(fp_line
			(start -1.7018 0.3048)
			(end -1.7018 1.8796)
			(stroke
				(width 0.508)
				(type default)
			)
			(layer "F.SilkS")
		)
		(fp_poly
			(pts
				(xy -1.179068 0.081534) (xy -1.179068 -0.081534) (xy 1.102868 -0.081534) (xy 1.102868 0.081534)
			)
			(stroke
				(width 0)
				(type default)
			)
			(fill yes)
			(layer "F.SilkS")
		)
		(fp_poly
			(pts
				(xy -1.4478 1.2446) (xy 1.4478 1.2446) (xy 1.4478 -1.2446) (xy -1.4478 -1.2446)
			)
			(stroke
				(width 0)
				(type default)
			)
			(fill no)
			(layer "F.CrtYd")
		)
		(fp_poly
			(pts
				(xy -1.4478 -1.23952) (xy -1.9558 -1.23952) (xy -1.9558 2.1336) (xy 1.9558 2.1336) (xy 1.9558 -2.1336)
				(xy -1.9558 -2.1336) (xy -1.9558 -1.2446) (xy 1.4478 -1.2446) (xy 1.4478 1.2446) (xy -1.4478 1.2446)
			)
			(stroke
				(width 0)
				(type default)
			)
			(fill no)
			(layer "F.CrtYd")
		)
		(fp_rect
			(start -1.9558 2.1336)
			(end 1.9558 -2.1336)
			(stroke
				(width 0)
				(type default)
			)
			(fill no)
			(layer "F.Fab")
		)
		(pad "1" smd rect
			(at -0.950468 0.995934 90)
			(size 0.4572 1.27)
			(layers "F.Cu" "F.Mask" "F.Paste")
			(net "PWRGD_PVDDQ_DEF")
		)
		(pad "2" smd rect
			(at 0 0.995934 90)
			(size 0.4572 1.27)
			(layers "F.Cu" "F.Mask" "F.Paste")
			(net "P12V_NVDIMM_DEF")
		)
		(pad "3" smd rect
			(at 0.950468 0.995934 90)
			(size 0.4572 1.27)
			(layers "F.Cu" "F.Mask" "F.Paste")
			(net "PWRGD_PVDDQ_DEF_N")
		)
		(pad "4" smd rect
			(at 0.950468 -0.995934 90)
			(size 0.4572 1.27)
			(layers "F.Cu" "F.Mask" "F.Paste")
			(net "P12V_NVDIMM_DEF_D")
		)
		(pad "5" smd rect
			(at 0 -0.995934 90)
			(size 0.4572 1.27)
			(layers "F.Cu" "F.Mask" "F.Paste")
			(net "GND")
		)
		(pad "6" smd rect
			(at -0.950468 -0.995934 90)
			(size 0.4572 1.27)
			(layers "F.Cu" "F.Mask" "F.Paste")
			(net "PWRGD_PVDDQ_DEF_N")
		)
	)
	(footprint ""
		(layer "F.Cu")
		(at 194.142614 -61.732668)
		(property "Reference" "CT6"
			(at -0.48387 -4.9022 270)
			(unlocked yes)
			(layer "F.SilkS")
			(effects
				(font
					(size 0.7874 0.5842)
					(thickness 0.1524)
				)
				(justify left)
			)
		)
		(property "Value" ""
			(at 0 0 0)
			(layer "F.Fab")
			(effects
				(font
					(size 1.27 1.27)
				)
			)
		)
		(duplicate_pad_numbers_are_jumpers no)
		(fp_poly
			(pts
				(xy 0.3048 -0.1016) (xy 0.3048 0.9906) (xy -0.3048 0.9906) (xy -0.3048 -0.1016)
			)
			(stroke
				(width 0)
				(type default)
			)
			(fill no)
			(layer "F.CrtYd")
		)
		(fp_line
			(start -0.3048 -0.1016)
			(end -0.3048 0.9906)
			(stroke
				(width 0.1)
				(type default)
			)
			(layer "F.Fab")
		)
		(fp_line
			(start -0.3048 0.9906)
			(end 0.3048 0.9906)
			(stroke
				(width 0.1)
				(type default)
			)
			(layer "F.Fab")
		)
		(fp_line
			(start 0.3048 -0.1016)
			(end -0.3048 -0.1016)
			(stroke
				(width 0.1)
				(type default)
			)
			(layer "F.Fab")
		)
		(fp_line
			(start 0.3048 0.9906)
			(end 0.3048 -0.1016)
			(stroke
				(width 0.1)
				(type default)
			)
			(layer "F.Fab")
		)
		(pad "1" smd rect
			(at 0 0)
			(size 0.508 0.508)
			(layers "F.Cu" "F.Mask" "F.Paste")
			(net "VR_PVCCIN_CPU0_AIREF2")
		)
		(pad "2" smd rect
			(at 0 0.889)
			(size 0.508 0.508)
			(layers "F.Cu" "F.Mask" "F.Paste")
			(net "GND")
		)
		(zone
			(layer "F.Cu")
			(hatch none 0.5)
			(connect_pads
				(clearance 0)
			)
			(min_thickness 0.25)
			(keepout
				(tracks allowed)
				(vias not_allowed)
				(pads allowed)
				(copperpour not_allowed)
				(footprints allowed)
			)
			(placement
				(enabled no)
				(sheetname "")
			)
			(fill
				(thermal_gap 0.5)
				(thermal_bridge_width 0.5)
				(island_removal_mode 0)
			)
			(polygon
				(pts
					(xy 193.888614 -61.478668) (xy 194.396614 -61.478668) (xy 194.396614 -61.097668) (xy 193.888614 -61.097668)
				)
			)
		)
		(zone
			(layer "F.Cu")
			(hatch none 0.5)
			(connect_pads
				(clearance 0)
			)
			(min_thickness 0.25)
			(keepout
				(tracks not_allowed)
				(vias allowed)
				(pads allowed)
				(copperpour not_allowed)
				(footprints allowed)
			)
			(placement
				(enabled no)
				(sheetname "")
			)
			(fill
				(thermal_gap 0.5)
				(thermal_bridge_width 0.5)
				(island_removal_mode 0)
			)
			(polygon
				(pts
					(xy 193.888614 -61.097668) (xy 194.396614 -61.097668) (xy 194.396614 -61.478668) (xy 193.888614 -61.478668)
				)
			)
		)
	)
)
